# T6G (Grand Teton) — schematic netlist excerpt (pin names and nets, part order shuffled) for the footprints in the layout excerpt that follows; sources: Cadence DE-HDL packaged netlist, KiCad conversion of 04192023_DAF0TMB3IC0_F0TG_MB_C_brd_V02_OCP.brd

J41  SCONN168_ME1016810202011  IO  pkg CON_F168S2H7D_P0-6W2-95_LUH  page 150
  GND_A1  = SMB_OCP_SFF_3V3AUX_SCL_R0
  GND_A2  = SMB_OCP_SFF_3V3AUX_SDA_R0
  GND_A3  = SMB_CPU0_CPU1_APML_SCL_R
  GND_A4  = SMB_CPU0_CPU1_APML_SDA_R
  GND_A5  = SMB_VR_3V3AUX_SCL_R0
  GND_A6  = SMB_VR_3V3AUX_SDA_R0
  SMCLK  = SMB_CPU0_CPU1_SEC_SCL_R
  SMDAT  = SMB_CPU0_CPU1_SEC_SDA_R
  \smrst#\  = I3C_BMC_SWB_SCL
  \prsnta#\  = I3C_BMC_SWB_SDA
  \perst1#\  = SMB_OCP_V3_2_3V3AUX_SCL_R0
  \prsntb2#\  = SMB_OCP_V3_2_3V3AUX_SDA_R0
  GND_A13  = GND
  REFCLKN1  = CLK_100M_CPU0_CLK01_DP
  REFCLKP1  = CLK_100M_CPU0_CLK01_DN
  GND_A16  = GND
  PERN0  = P2E_CPU0_P5_TX_C_DP
  PERP0  = P2E_CPU0_P5_TX_C_DN
  GND_A19  = GND
  PERN1  = P2E_CPU0_P5_RX_DP
  PERP1  = P2E_CPU0_P5_RX_DN
  GND_A22  = GND
  PERN2  = SMB_PCIE0_3V3AUX_SCL
  PERP2  = SMB_PCIE0_3V3AUX_SDA
  GND_A25  = SMB_PMBUS_3V3AUX_SCL_R0
  PERN3  = SMB_PMBUS_3V3AUX_SDA_R0
  PERP3  = SMB_1_PLD_3V3AUX_SCL_R3
  GND_A28  = SMB_1_PLD_3V3AUX_SDA_R3
  GND_A29  = SMB_FAN_3V3AUX_SCL
  PERN4  = SMB_FAN_3V3AUX_SDA
  PERP4  = SMB_PCIE2_3V3AUX_SCL_R0
  GND_A32  = SMB_PCIE2_3V3AUX_SDA_R0
  PERN5  = GND
  PERP5  = JTAG_SCM_TCK
  GND_A35  = JTAG_SCM_TMS
  PERN6  = JTAG_SCM_TDI_R
  PERP6  = JTAG_SCM_TDO_R
  GND_A38  = SMB_PCIE3_3V3AUX_SCL_R
  PERN7  = SMB_PCIE3_3V3AUX_SDA_R
  PERP7  = SMB_HOST_CLK_3V3AUX_SCL_R0
  GND_A41  = SMB_HOST_CLK_3V3AUX_SDA_R0
  \prsntb1#\  = GND
  GND_A43  = FW_RECOVERY
  PERN8  = PWRGD_PS_PWROK_R
  PERP8  = TP_STBY_EN
  GND_A46  = RST_MB_STBY_R_N
  PERN9  = SCM_SYS_PWRBTN_R_N
  PERP9  = SCM_SYS_PWROK_R1
  GND_A49  = SCM_HDT_DBREQ_N
  PERN10  = PU_JTAG_DBP_BMC_PRDY_N
  PERP10  = FM_RST_PERST_SCM_N
  GND_A52  = FM_UARTSW_MSB_R
  PERN11  = SCM_ROT_CPU_RST_N
  PERP11  = TP_CHASI
  GND_A55  = FM_UARTSW_LSB_R
  PERN12  = IRQ0_A56
  PERP12  = FM_SCM_PRSNT1_N
  GND_A58  = GND
  PERN13  = USB3_CPU0_BMC_RX_DP
  PERP13  = USB3_CPU0_BMC_RX_DN
  GND_A61  = GND
  PERN14  = TP_PCIE_RXP<1>
  PERP14  = TP_PCIE_RXN<1>
  GND_A64  = GND
  PERN15  = P2E_MB_BMC_RX_BUF_DP<0>
  PERP15  = P2E_MB_BMC_RX_BUF_DN<0>
  GND_A67  = GND
  USB_DATN  = CLK_100M_BMC_RC_DP
  USB_DATP  = CLK_100M_BMC_RC_DN
  \pwrbrk0#\  = GND
  \+12v_edge_b1\  = CLK_ESPI_CPU0_CLK1
  \+12v_edge_b2\  = ESPI_CPU0_CS1_N
  \+12v_edge_b3\  = ESPI_CPU0_ALERT_N
  \+12v_edge_b4\  = RST_ESPI_CPU0_RSTOUT_N
  \+12v_edge_b5\  = ESPI_CPU0_D0
  \+12v_edge_b6\  = ESPI_CPU0_D1
  \bif0#\  = ESPI_CPU0_D2
  \bif1#\  = ESPI_CPU0_D3
  \bif2#\  = FM_LPC_ESPI_SEL
  \perst0#\  = GND
  \+3.3v_edge\  = SPI_CPU0_LVC3_SCM_CLK
  AUX_PWR_EN  = SPI_CPU0_LVC3_SCM_CS0_N
  GND_B13  = SPI_CPU0_LVC3_SCM_D0
  REFCLKN0  = SPI_CPU0_LVC3_SCM_D1
  REFCLKP0  = SPI_CPU0_LVC3_SCM_D2
  GND_B16  = SPI_CPU0_LVC3_SCM_D3
  PETN0  = GND
  PETP0  = CLK_50M_RMII_BMC_OCP
  GND_B19  = RMII_OCP_BMC_CRSDV
  PETN1  = RMII_BMC_OCP_TX_EN
  PETP1  = RMII_BMC_OCP_TXD_0
  GND_B22  = RMII_BMC_OCP_TXD_1
  PETN2  = RMII_BMC_OCP_RX_ER
  PETP2  = RMII_OCP_BMC_RXD_0
  GND_B25  = RMII_OCP_BMC_RXD_1
  PETN3  = GND
  PETP3  = TP_PECI_BMC
  GND_B28  = TP_PVCCIO_PECI_BMC
  GND_B29  = SGPIO_SCM_DO_R_<0>
  PETN4  = SGPIO_SCM_CLK_R_<0>
  PETP4  = SGPIO_SCM_DI_R_<0>
  GND_B32  = SGPIO_SCM_LD_R_<0>
  PETN5  = GND
  PETP5  = SGPIO_SCM_DO_R_<1>
  GND_B35  = SGPIO_SCM_CLK_R_<1>
  PETN6  = SGPIO_SCM_DI_R_<1>
  PETP6  = SGPIO_SCM_LD_R_<1>
  GND_B38  = GND
  PETN7  = SGPIO_SCM_RESET_R_N
  PETP7  = SGPIO_SCM_INTR_R1_N
  GND_B41  = SCM_VDD_RTC
  \prsntb0#\  = FM_AC_PWR_BTN_N
  GND_B43  = TP_SPI_2_PLD_CLK
  PETN8  = TP_SPI_2_PLD_CS_N
  PETP8  = TP_SPI_2_PLD_IO0
  GND_B46  = TP_SPI_2_PLD_IO1
  PETN9  = TP_SPI_2_PLD_IO2
  PETP9  = TP_SPI_2_PLD_IO3
  GND_B49  = GND
  PETN10  = USB2_HOST_BMC_B_DP
  PETP10  = USB2_HOST_BMC_B_DN
  GND_B52  = GND
  PETN11  = USB2_CPU0_P1_DP
  PETP11  = USB2_CPU0_P1_DN
  GND_B55  = GND
  PETN12  = USB2_HUB_EXT_DP
  PETP12  = USB2_HUB_EXT_DN
  GND_B58  = GND
  PETN13  = USB3_CPU0_BMC_TX_BUF_C_DP
  PETP13  = USB3_CPU0_BMC_TX_BUF_C_DN
  GND_B61  = GND
  PETN14  = TP_PCIE_TXP<1>
  PETP14  = TP_PCIE_TXN<1>
  GND_B64  = GND
  PETN15  = P2E_MB_BMC_TX_C_DP<0>
  PETP15  = P2E_MB_BMC_TX_C_DN<0>
  GND_B67  = GND
  RFU1_NC_B68  = TP_PCIE_TXP<3>
  RFU1_NC_B69  = TP_BEEP_LED
  \prsntb3#\  = GND
  G1  = GND
  G2  = GND
  G3  = GND
  G4  = GND
  G5  = GND
  \perst2#\  = P12V_SCM
  \perst3#\  = P12V_SCM
  \wake#\  = GND
  RBT_ARB_IN  = GND
  RBT_ARB_OUT  = I3C_SCM_0_SCL
  SLOT_ID1  = I3C_SCM_0_SDA
  RBT_TX_EN  = I3C_SCM_1_SCL
  RBT_TXD1  = I3C_SCM_1_SDA
  RBT_TXD0  = I3C_SCM_2_SCL
  GND_OA10  = I3C_SCM_2_SDA
  REFCLKN3  = I3C_SCM_3_SCL
  REFCLKP3  = I3C_SCM_3_SDA
  GND_OA13  = GND
  RBT_CLK_IN  = VIRTUAL_RESEAT
  NIC_PWR_GOOD  = P12V_SCM
  MAIN_PWR_EN  = P12V_SCM
  \ld#\  = PRSNT0_N
  DATA_IN  = GND
  DATA_OUT  = UART_BMC_BIC_TX
  CLK  = UART_BMC_BIC_BUF_RX
  SLOT_ID0  = GND
  RBT_RXD1  = UART_CPU0_SCM_LVC3_UART1_RX
  RBT_RXD0  = UART_CPU0_SCM_LVC3_UART1_R1_TX
  GND_OB10  = GND
  REFCLKN2  = RST_SRST_PLD_BMC_N
  REFCLKP2  = SPI_CPU0_LVC3_TPM_CS_N
  GND_OB13  = FPGA_IO3V3_RSVD_1
  RBT_CRS_DV  = FM_SOL_UART_CH_SEL_R

(kicad_pcb
	(version 20260206)
	(generator "pcbnew")
	(generator_version "10.0")
	(general
		(thickness 1.6)
		(legacy_teardrops no)
	)
	(paper "A4")
	(title_block
		(title "04192023_DAF0TMB3IC0_F0TG_MB_C_brd_V02_OCP.brd")
		(comment 1 "Grand Teton / footprint 3166 of 8354 (J41), pads 1-42 of 175")
	)
	(layers
		(0 "F.Cu" signal "TOP")
		(4 "In1.Cu" signal "GND")
		(6 "In2.Cu" signal "IN1")
		(8 "In3.Cu" signal "GND1")
		(10 "In4.Cu" signal "IN2")
		(12 "In5.Cu" signal "GND2")
		(14 "In6.Cu" signal "IN3")
		(16 "In7.Cu" signal "GND3")
		(18 "In8.Cu" signal "VCC")
		(20 "In9.Cu" signal "VCC1")
		(22 "In10.Cu" signal "GND4")
		(24 "In11.Cu" signal "IN4")
		(26 "In12.Cu" signal "GND5")
		(28 "In13.Cu" signal "IN5")
		(30 "In14.Cu" signal "GND6")
		(32 "In15.Cu" signal "IN6")
		(34 "In16.Cu" signal "GND7")
		(2 "B.Cu" signal "BOTTOM")
		(9 "F.Adhes" user "F.Adhesive")
		(11 "B.Adhes" user "B.Adhesive")
		(13 "F.Paste" user "Package Geometry/Pastemask Top")
		(15 "B.Paste" user "Package Geometry/Pastemask Bottom")
		(5 "F.SilkS" user "Ref Des/Silkscreen Top")
		(7 "B.SilkS" user "Ref Des/Silkscreen Bottom")
		(1 "F.Mask" user "Board Geometry/Soldermask Top")
		(3 "B.Mask" user "Board Geometry/Soldermask Bottom")
		(17 "Dwgs.User" user "User.Drawings")
		(19 "Cmts.User" user "User.Comments")
		(21 "Eco1.User" user "User.Eco1")
		(23 "Eco2.User" user "User.Eco2")
		(25 "Edge.Cuts" user "Board Geometry/Outline")
		(27 "Margin" user)
		(31 "F.CrtYd" user "Package Geometry/Place Bound Top")
		(29 "B.CrtYd" user "Package Geometry/Place Bound Bottom")
		(35 "F.Fab" user "Ref Des/Assembly Top")
		(33 "B.Fab" user "Ref Des/Assembly Bottom")
	)
	(footprint ""
		(layer "F.Cu")
		(at 160.402016 -10.849864 -90)
		(property "Reference" "J41"
			(at -8.65886 -21.78558 0)
			(unlocked yes)
			(layer "F.SilkS")
			(effects
				(font
					(size 0.7874 0.5842)
					(thickness 0.1524)
				)
				(justify left)
			)
		)
		(property "Value" ""
			(at 0 0 270)
			(layer "F.Fab")
			(effects
				(font
					(size 1.27 1.27)
				)
			)
		)
		(duplicate_pad_numbers_are_jumpers no)
		(pad "" np_thru_hole circle
			(at -0.599948 -32.079946 180)
			(size 1.1176 1.1176)
			(drill 1.1176)
			(layers "*.Cu" "*.Mask")
			(clearance 0.381)
			(thermal_gap 0.381)
		)
		(pad "" np_thru_hole circle
			(at 0.40005 32.085026 180)
			(size 1.1176 1.1176)
			(drill 1.1176)
			(layers "*.Cu" "*.Mask")
			(clearance 0.381)
			(thermal_gap 0.381)
		)
		(pad "A1" smd rect
			(at -2.750058 -18.465038 180)
			(size 0.381 1.4478)
			(layers "F.Cu" "F.Mask" "F.Paste")
			(net "SMB_OCP_SFF_3V3AUX_SCL_R0")
		)
		(pad "A2" smd rect
			(at -2.750058 -17.86509 180)
			(size 0.381 1.4478)
			(layers "F.Cu" "F.Mask" "F.Paste")
			(net "SMB_OCP_SFF_3V3AUX_SDA_R0")
		)
		(pad "A3" smd rect
			(at -2.750058 -17.264888 180)
			(size 0.381 1.4478)
			(layers "F.Cu" "F.Mask" "F.Paste")
			(net "SMB_CPU0_CPU1_APML_SCL_R")
		)
		(pad "A4" smd rect
			(at -2.750058 -16.66494 180)
			(size 0.381 1.4478)
			(layers "F.Cu" "F.Mask" "F.Paste")
			(net "SMB_CPU0_CPU1_APML_SDA_R")
		)
		(pad "A5" smd rect
			(at -2.750058 -16.064992 180)
			(size 0.381 1.4478)
			(layers "F.Cu" "F.Mask" "F.Paste")
			(net "SMB_VR_3V3AUX_SCL_R0")
		)
		(pad "A6" smd rect
			(at -2.750058 -15.465044 180)
			(size 0.381 1.4478)
			(layers "F.Cu" "F.Mask" "F.Paste")
			(net "SMB_VR_3V3AUX_SDA_R0")
		)
		(pad "A7" smd rect
			(at -2.750058 -14.865096 180)
			(size 0.381 1.4478)
			(layers "F.Cu" "F.Mask" "F.Paste")
			(net "SMB_CPU0_CPU1_SEC_SCL_R")
		)
		(pad "A8" smd rect
			(at -2.750058 -14.264894 180)
			(size 0.381 1.4478)
			(layers "F.Cu" "F.Mask" "F.Paste")
			(net "SMB_CPU0_CPU1_SEC_SDA_R")
		)
		(pad "A9" smd rect
			(at -2.750058 -13.664946 180)
			(size 0.381 1.4478)
			(layers "F.Cu" "F.Mask" "F.Paste")
			(net "I3C_BMC_SWB_SCL")
		)
		(pad "A10" smd rect
			(at -2.750058 -13.064998 180)
			(size 0.381 1.4478)
			(layers "F.Cu" "F.Mask" "F.Paste")
			(net "I3C_BMC_SWB_SDA")
		)
		(pad "A11" smd rect
			(at -2.750058 -12.46505 180)
			(size 0.381 1.4478)
			(layers "F.Cu" "F.Mask" "F.Paste")
			(net "SMB_OCP_V3_2_3V3AUX_SCL_R0")
		)
		(pad "A12" smd rect
			(at -2.750058 -11.865102 180)
			(size 0.381 1.4478)
			(layers "F.Cu" "F.Mask" "F.Paste")
			(net "SMB_OCP_V3_2_3V3AUX_SDA_R0")
		)
		(pad "A13" smd rect
			(at -2.750058 -11.2649 180)
			(size 0.381 1.4478)
			(layers "F.Cu" "F.Mask" "F.Paste")
			(net "GND")
		)
		(pad "A14" smd rect
			(at -2.750058 -10.664952 180)
			(size 0.381 1.4478)
			(layers "F.Cu" "F.Mask" "F.Paste")
			(net "CLK_100M_CPU0_CLK01_DP")
		)
		(pad "A15" smd rect
			(at -2.750058 -10.065004 180)
			(size 0.381 1.4478)
			(layers "F.Cu" "F.Mask" "F.Paste")
			(net "CLK_100M_CPU0_CLK01_DN")
		)
		(pad "A16" smd rect
			(at -2.750058 -9.465056 180)
			(size 0.381 1.4478)
			(layers "F.Cu" "F.Mask" "F.Paste")
			(net "GND")
		)
		(pad "A17" smd rect
			(at -2.750058 -8.865108 180)
			(size 0.381 1.4478)
			(layers "F.Cu" "F.Mask" "F.Paste")
			(net "P2E_CPU0_P5_TX_C_DP")
		)
		(pad "A18" smd rect
			(at -2.750058 -8.264906 180)
			(size 0.381 1.4478)
			(layers "F.Cu" "F.Mask" "F.Paste")
			(net "P2E_CPU0_P5_TX_C_DN")
		)
		(pad "A19" smd rect
			(at -2.750058 -7.664958 180)
			(size 0.381 1.4478)
			(layers "F.Cu" "F.Mask" "F.Paste")
			(net "GND")
		)
		(pad "A20" smd rect
			(at -2.750058 -7.06501 180)
			(size 0.381 1.4478)
			(layers "F.Cu" "F.Mask" "F.Paste")
			(net "P2E_CPU0_P5_RX_DP")
		)
		(pad "A21" smd rect
			(at -2.750058 -6.465062 180)
			(size 0.381 1.4478)
			(layers "F.Cu" "F.Mask" "F.Paste")
			(net "P2E_CPU0_P5_RX_DN")
		)
		(pad "A22" smd rect
			(at -2.750058 -5.865114 180)
			(size 0.381 1.4478)
			(layers "F.Cu" "F.Mask" "F.Paste")
			(net "GND")
		)
		(pad "A23" smd rect
			(at -2.750058 -5.264912 180)
			(size 0.381 1.4478)
			(layers "F.Cu" "F.Mask" "F.Paste")
			(net "SMB_PCIE0_3V3AUX_SCL")
		)
		(pad "A24" smd rect
			(at -2.750058 -4.664964 180)
			(size 0.381 1.4478)
			(layers "F.Cu" "F.Mask" "F.Paste")
			(net "SMB_PCIE0_3V3AUX_SDA")
		)
		(pad "A25" smd rect
			(at -2.750058 -4.065016 180)
			(size 0.381 1.4478)
			(layers "F.Cu" "F.Mask" "F.Paste")
			(net "SMB_PMBUS_3V3AUX_SCL_R0")
		)
		(pad "A26" smd rect
			(at -2.750058 -3.465068 180)
			(size 0.381 1.4478)
			(layers "F.Cu" "F.Mask" "F.Paste")
			(net "SMB_PMBUS_3V3AUX_SDA_R0")
		)
		(pad "A27" smd rect
			(at -2.750058 -2.86512 180)
			(size 0.381 1.4478)
			(layers "F.Cu" "F.Mask" "F.Paste")
			(net "SMB_1_PLD_3V3AUX_SCL_R3")
		)
		(pad "A28" smd rect
			(at -2.750058 -2.264918 180)
			(size 0.381 1.4478)
			(layers "F.Cu" "F.Mask" "F.Paste")
			(net "SMB_1_PLD_3V3AUX_SDA_R3")
		)
		(pad "A29" smd rect
			(at -2.750058 1.74498 180)
			(size 0.381 1.4478)
			(layers "F.Cu" "F.Mask" "F.Paste")
			(net "SMB_FAN_3V3AUX_SCL")
		)
		(pad "A30" smd rect
			(at -2.750058 2.344928 180)
			(size 0.381 1.4478)
			(layers "F.Cu" "F.Mask" "F.Paste")
			(net "SMB_FAN_3V3AUX_SDA")
		)
		(pad "A31" smd rect
			(at -2.750058 2.944876 180)
			(size 0.381 1.4478)
			(layers "F.Cu" "F.Mask" "F.Paste")
			(net "SMB_PCIE2_3V3AUX_SCL_R0")
		)
		(pad "A32" smd rect
			(at -2.750058 3.545078 180)
			(size 0.381 1.4478)
			(layers "F.Cu" "F.Mask" "F.Paste")
			(net "SMB_PCIE2_3V3AUX_SDA_R0")
		)
		(pad "A33" smd rect
			(at -2.750058 4.145026 180)
			(size 0.381 1.4478)
			(layers "F.Cu" "F.Mask" "F.Paste")
			(net "GND")
		)
		(pad "A34" smd rect
			(at -2.750058 4.744974 180)
			(size 0.381 1.4478)
			(layers "F.Cu" "F.Mask" "F.Paste")
			(net "JTAG_SCM_TCK")
		)
		(pad "A35" smd rect
			(at -2.750058 5.344922 180)
			(size 0.381 1.4478)
			(layers "F.Cu" "F.Mask" "F.Paste")
			(net "JTAG_SCM_TMS")
		)
		(pad "A36" smd rect
			(at -2.750058 5.945124 180)
			(size 0.381 1.4478)
			(layers "F.Cu" "F.Mask" "F.Paste")
			(net "JTAG_SCM_TDI_R")
		)
		(pad "A37" smd rect
			(at -2.750058 6.545072 180)
			(size 0.381 1.4478)
			(layers "F.Cu" "F.Mask" "F.Paste")
			(net "JTAG_SCM_TDO_R")
		)
		(pad "A38" smd rect
			(at -2.750058 7.14502 180)
			(size 0.381 1.4478)
			(layers "F.Cu" "F.Mask" "F.Paste")
			(net "SMB_PCIE3_3V3AUX_SCL_R")
		)
		(pad "A39" smd rect
			(at -2.750058 7.744968 180)
			(size 0.381 1.4478)
			(layers "F.Cu" "F.Mask" "F.Paste")
			(net "SMB_PCIE3_3V3AUX_SDA_R")
		)
		(pad "A40" smd rect
			(at -2.750058 8.344916 180)
			(size 0.381 1.4478)
			(layers "F.Cu" "F.Mask" "F.Paste")
			(net "SMB_HOST_CLK_3V3AUX_SCL_R0")
		)
	)
)
